# T6G (Grand Teton) — schematic netlist excerpt (pin names and nets, part order shuffled) for the footprints in the layout excerpt that follows; sources: Cadence DE-HDL packaged netlist, KiCad conversion of 04192023_DAF0TMB3IC0_F0TG_MB_C_brd_V02_OCP.brd

C647  Q_CAP  1UF 4V 20% X6S  pkg 0201  page 290 : A = P0V9_CPU0_RT1_2A ; B = GND
PC123_6  Q_CAP  22UF 4V 20% X6S  pkg C0805  page 203 : A = PVDDCR_CPU1_P0 ; B = GND
R802  Q_RES  0 5% CHIP  pkg 0201LF  page 185 : A = SMB_RT_CPU1_P0_ROM_MUX_2D_SCL ; B = SMB_RT_CPU1_P0_ROM_MUX_2D_R_SCL
C383  Q_CAP  0.1UF 10V 10% X7S  pkg C0201  page 345 : A = P0V9_CPU1_RT_2D ; B = GND

(kicad_pcb
	(version 20260206)
	(generator "pcbnew")
	(generator_version "10.0")
	(general
		(thickness 1.6)
		(legacy_teardrops no)
	)
	(paper "A4")
	(title_block
		(title "04192023_DAF0TMB3IC0_F0TG_MB_C_brd_V02_OCP.brd")
		(comment 1 "Grand Teton / footprints 6361-6364 of 8354")
	)
	(layers
		(0 "F.Cu" signal "TOP")
		(4 "In1.Cu" signal "GND")
		(6 "In2.Cu" signal "IN1")
		(8 "In3.Cu" signal "GND1")
		(10 "In4.Cu" signal "IN2")
		(12 "In5.Cu" signal "GND2")
		(14 "In6.Cu" signal "IN3")
		(16 "In7.Cu" signal "GND3")
		(18 "In8.Cu" signal "VCC")
		(20 "In9.Cu" signal "VCC1")
		(22 "In10.Cu" signal "GND4")
		(24 "In11.Cu" signal "IN4")
		(26 "In12.Cu" signal "GND5")
		(28 "In13.Cu" signal "IN5")
		(30 "In14.Cu" signal "GND6")
		(32 "In15.Cu" signal "IN6")
		(34 "In16.Cu" signal "GND7")
		(2 "B.Cu" signal "BOTTOM")
		(9 "F.Adhes" user "F.Adhesive")
		(11 "B.Adhes" user "B.Adhesive")
		(13 "F.Paste" user "Package Geometry/Pastemask Top")
		(15 "B.Paste" user "Package Geometry/Pastemask Bottom")
		(5 "F.SilkS" user "Ref Des/Silkscreen Top")
		(7 "B.SilkS" user "Ref Des/Silkscreen Bottom")
		(1 "F.Mask" user "Board Geometry/Soldermask Top")
		(3 "B.Mask" user "Board Geometry/Soldermask Bottom")
		(17 "Dwgs.User" user "User.Drawings")
		(19 "Cmts.User" user "User.Comments")
		(21 "Eco1.User" user "User.Eco1")
		(23 "Eco2.User" user "User.Eco2")
		(25 "Edge.Cuts" user "Board Geometry/Outline")
		(27 "Margin" user)
		(31 "F.CrtYd" user "Package Geometry/Place Bound Top")
		(29 "B.CrtYd" user "Package Geometry/Place Bound Bottom")
		(35 "F.Fab" user "Ref Des/Assembly Top")
		(33 "B.Fab" user "Ref Des/Assembly Bottom")
	)
	(footprint ""
		(layer "B.Cu")
		(at 337.106006 -395.148562 90)
		(property "Reference" "C647"
			(at 0 0 90)
			(layer "B.SilkS")
			(hide yes)
			(effects
				(font
					(size 1.27 1.27)
				)
				(justify mirror)
			)
		)
		(property "Value" ""
			(at 0 0 90)
			(layer "B.Fab")
			(effects
				(font
					(size 1.27 1.27)
				)
				(justify mirror)
			)
		)
		(duplicate_pad_numbers_are_jumpers no)
		(fp_line
			(start 0.299974 -0.150114)
			(end -0.299974 -0.150114)
			(stroke
				(width 0.1)
				(type default)
			)
			(layer "B.Fab")
		)
		(fp_line
			(start -0.299974 -0.150114)
			(end -0.299974 0.150114)
			(stroke
				(width 0.1)
				(type default)
			)
			(layer "B.Fab")
		)
		(fp_line
			(start 0.299974 0.150114)
			(end 0.299974 -0.150114)
			(stroke
				(width 0.1)
				(type default)
			)
			(layer "B.Fab")
		)
		(fp_line
			(start -0.299974 0.150114)
			(end 0.299974 0.150114)
			(stroke
				(width 0.1)
				(type default)
			)
			(layer "B.Fab")
		)
		(pad "1" smd rect
			(at 0.2667 0 270)
			(size 0.3048 0.381)
			(layers "B.Cu" "B.Mask" "B.Paste")
			(net "P0V9_CPU0_RT1_2A")
		)
		(pad "2" smd rect
			(at -0.2667 0 270)
			(size 0.3048 0.381)
			(layers "B.Cu" "B.Mask" "B.Paste")
			(net "GND")
		)
	)
	(footprint ""
		(layer "B.Cu")
		(at 355.727508 -331.304646 -90)
		(property "Reference" "PC123_6"
			(at 0 0 90)
			(layer "B.SilkS")
			(hide yes)
			(effects
				(font
					(size 1.27 1.27)
				)
				(justify mirror)
			)
		)
		(property "Value" ""
			(at 0 0 90)
			(layer "B.Fab")
			(effects
				(font
					(size 1.27 1.27)
				)
				(justify mirror)
			)
		)
		(duplicate_pad_numbers_are_jumpers no)
		(fp_line
			(start -1.524 0.762)
			(end 1.524 0.762)
			(stroke
				(width 0.1524)
				(type default)
			)
			(layer "B.SilkS")
		)
		(fp_line
			(start 1.524 0.762)
			(end 1.524 -0.762)
			(stroke
				(width 0.1524)
				(type default)
			)
			(layer "B.SilkS")
		)
		(fp_line
			(start -1.524 -0.762)
			(end -1.524 0.762)
			(stroke
				(width 0.1524)
				(type default)
			)
			(layer "B.SilkS")
		)
		(fp_line
			(start 1.524 -0.762)
			(end -1.524 -0.762)
			(stroke
				(width 0.1524)
				(type default)
			)
			(layer "B.SilkS")
		)
		(fp_line
			(start -1.1049 0.724916)
			(end -1.1049 -0.724916)
			(stroke
				(width 0.1)
				(type default)
			)
			(layer "B.Fab")
		)
		(fp_line
			(start 1.1049 0.724916)
			(end -1.1049 0.724916)
			(stroke
				(width 0.1)
				(type default)
			)
			(layer "B.Fab")
		)
		(fp_line
			(start -1.1049 -0.724916)
			(end 1.1049 -0.724916)
			(stroke
				(width 0.1)
				(type default)
			)
			(layer "B.Fab")
		)
		(fp_line
			(start 1.1049 -0.724916)
			(end 1.1049 0.724916)
			(stroke
				(width 0.1)
				(type default)
			)
			(layer "B.Fab")
		)
		(pad "1" smd rect
			(at 0.889 0 270)
			(size 1.016 1.27)
			(layers "B.Cu" "B.Mask" "B.Paste")
			(net "PVDDCR_CPU1_P0")
		)
		(pad "2" smd rect
			(at -0.889 0 270)
			(size 1.016 1.27)
			(layers "B.Cu" "B.Mask" "B.Paste")
			(net "GND")
		)
	)
	(footprint ""
		(layer "B.Cu")
		(at 153.146252 -388.011162 -90)
		(property "Reference" "C383"
			(at 0 0 90)
			(layer "B.SilkS")
			(hide yes)
			(effects
				(font
					(size 1.27 1.27)
				)
				(justify mirror)
			)
		)
		(property "Value" ""
			(at 0 0 90)
			(layer "B.Fab")
			(effects
				(font
					(size 1.27 1.27)
				)
				(justify mirror)
			)
		)
		(duplicate_pad_numbers_are_jumpers no)
		(fp_line
			(start -0.299974 0.150114)
			(end 0.299974 0.150114)
			(stroke
				(width 0.1)
				(type default)
			)
			(layer "B.Fab")
		)
		(fp_line
			(start 0.299974 0.150114)
			(end 0.299974 -0.150114)
			(stroke
				(width 0.1)
				(type default)
			)
			(layer "B.Fab")
		)
		(fp_line
			(start -0.299974 -0.150114)
			(end -0.299974 0.150114)
			(stroke
				(width 0.1)
				(type default)
			)
			(layer "B.Fab")
		)
		(fp_line
			(start 0.299974 -0.150114)
			(end -0.299974 -0.150114)
			(stroke
				(width 0.1)
				(type default)
			)
			(layer "B.Fab")
		)
		(pad "1" smd rect
			(at 0.2667 0 90)
			(size 0.3048 0.381)
			(layers "B.Cu" "B.Mask" "B.Paste")
			(net "P0V9_CPU1_RT_2D")
		)
		(pad "2" smd rect
			(at -0.2667 0 90)
			(size 0.3048 0.381)
			(layers "B.Cu" "B.Mask" "B.Paste")
			(net "GND")
		)
	)
	(footprint ""
		(layer "B.Cu")
		(at 238.633 -335.026 180)
		(property "Reference" "R802"
			(at 0 0 0)
			(layer "B.SilkS")
			(hide yes)
			(effects
				(font
					(size 1.27 1.27)
				)
				(justify mirror)
			)
		)
		(property "Value" ""
			(at 0 0 0)
			(layer "B.Fab")
			(effects
				(font
					(size 1.27 1.27)
				)
				(justify mirror)
			)
		)
		(duplicate_pad_numbers_are_jumpers no)
		(fp_line
			(start 0.32512 0.175006)
			(end 0.32512 -0.175006)
			(stroke
				(width 0.1)
				(type default)
			)
			(layer "B.Fab")
		)
		(fp_line
			(start 0.32512 -0.175006)
			(end -0.32512 -0.175006)
			(stroke
				(width 0.1)
				(type default)
			)
			(layer "B.Fab")
		)
		(fp_line
			(start -0.32512 0.175006)
			(end 0.32512 0.175006)
			(stroke
				(width 0.1)
				(type default)
			)
			(layer "B.Fab")
		)
		(fp_line
			(start -0.32512 -0.175006)
			(end -0.32512 0.175006)
			(stroke
				(width 0.1)
				(type default)
			)
			(layer "B.Fab")
		)
		(pad "1" smd rect
			(at 0.2667 0)
			(size 0.3048 0.381)
			(layers "B.Cu" "B.Mask" "B.Paste")
			(net "SMB_RT_CPU1_P0_ROM_MUX_2D_SCL")
		)
		(pad "2" smd rect
			(at -0.2667 0 180)
			(size 0.3048 0.381)
			(layers "B.Cu" "B.Mask" "B.Paste")
			(net "SMB_RT_CPU1_P0_ROM_MUX_2D_R_SCL")
		)
	)
)
